# BASEBOARD_FAB2 (Tioga Pass) — schematic netlist excerpt (pin names and nets, part order shuffled) for the footprints in the layout excerpt that follows; sources: Cadence DE-HDL packaged netlist, KiCad conversion of Wiwynn_Tioga_Pass_MB.brd

U2T1  PI3B3257A  IC  pkg TSSOPLF  page 154
  S  = FM_BIOS_SPI_BMC_CTRL
  IA0  = SPI_PCH_IO2_R1
  IA1  = TP_SPI_SWITCH1_3
  YA  = SPI_BIOS_SOCKET_IO2
  IB0  = SPI_PCH_IO3_R1
  IB1  = TP_SPI_SWITCH1_6
  YB  = SPI_BIOS_SOCKET_IO3
  GND  = GND
  YC  = TP_SPI_SWITCH1_9
  IC1  = TP_SPI_SWITCH1_10
  IC0  = TP_SPI_SWITCH1_11
  YD  = TP_SPI_SWITCH1_12
  ID1  = TP_SPI_SWITCH1_13
  ID0  = TP_SPI_SWITCH1_14
  EN  = GND
  VCC  = P3V3_STBY

R3N21  RES  100.0 1% CHIP  pkg 0402  page 212 : A = VSENSE_PVCCIO_CPU0_AVSP ; B = PVCCIO_CPU0

(kicad_pcb
	(version 20260206)
	(generator "pcbnew")
	(generator_version "10.0")
	(general
		(thickness 1.6)
		(legacy_teardrops no)
	)
	(paper "A4")
	(title_block
		(title "Wiwynn_Tioga_Pass_MB.brd")
		(comment 1 "Tioga Pass / footprints 3576-3577 of 4770")
	)
	(layers
		(0 "F.Cu" signal "TOP")
		(4 "In1.Cu" signal "L2GND")
		(6 "In2.Cu" signal "L3")
		(8 "In3.Cu" signal "L4GND")
		(10 "In4.Cu" signal "L5")
		(12 "In5.Cu" signal "L6GND")
		(14 "In6.Cu" signal "L7VCC")
		(16 "In7.Cu" signal "L8VCC")
		(18 "In8.Cu" signal "L9GND")
		(20 "In9.Cu" signal "L10")
		(22 "In10.Cu" signal "L11GND")
		(24 "In11.Cu" signal "L12")
		(26 "In12.Cu" signal "L13GND")
		(2 "B.Cu" signal "BOTTOM")
		(9 "F.Adhes" user "F.Adhesive")
		(11 "B.Adhes" user "B.Adhesive")
		(13 "F.Paste" user "Package Geometry/Pastemask Top")
		(15 "B.Paste" user "Package Geometry/Pastemask Bottom")
		(5 "F.SilkS" user "Ref Des/Silkscreen Top")
		(7 "B.SilkS" user "Ref Des/Silkscreen Bottom")
		(1 "F.Mask" user "Board Geometry/Soldermask Top")
		(3 "B.Mask" user "Board Geometry/Soldermask Bottom")
		(17 "Dwgs.User" user "User.Drawings")
		(19 "Cmts.User" user "User.Comments")
		(21 "Eco1.User" user "User.Eco1")
		(23 "Eco2.User" user "User.Eco2")
		(25 "Edge.Cuts" user "Board Geometry/Outline")
		(27 "Margin" user)
		(31 "F.CrtYd" user "Package Geometry/Place Bound Top")
		(29 "B.CrtYd" user "Package Geometry/Place Bound Bottom")
		(35 "F.Fab" user "Ref Des/Assembly Top")
		(33 "B.Fab" user "Ref Des/Assembly Bottom")
	)
	(footprint ""
		(layer "B.Cu")
		(at 354.597208 -89.97188 180)
		(property "Reference" "R3N21"
			(at 0 0 0)
			(layer "B.SilkS")
			(hide yes)
			(effects
				(font
					(size 1.27 1.27)
				)
				(justify mirror)
			)
		)
		(property "Value" ""
			(at 0 0 0)
			(layer "B.Fab")
			(effects
				(font
					(size 1.27 1.27)
				)
				(justify mirror)
			)
		)
		(duplicate_pad_numbers_are_jumpers no)
		(fp_poly
			(pts
				(xy 0.2794 -0.1016) (xy -0.2794 -0.1016) (xy -0.2794 0.9906) (xy 0.2794 0.9906)
			)
			(stroke
				(width 0)
				(type default)
			)
			(fill no)
			(layer "B.CrtYd")
		)
		(fp_line
			(start 0.2794 0.9906)
			(end -0.2794 0.9906)
			(stroke
				(width 0.1)
				(type default)
			)
			(layer "B.Fab")
		)
		(fp_line
			(start 0.2794 -0.1016)
			(end 0.2794 0.9906)
			(stroke
				(width 0.1)
				(type default)
			)
			(layer "B.Fab")
		)
		(fp_line
			(start -0.2794 0.9906)
			(end -0.2794 -0.1016)
			(stroke
				(width 0.1)
				(type default)
			)
			(layer "B.Fab")
		)
		(fp_line
			(start -0.2794 -0.1016)
			(end 0.2794 -0.1016)
			(stroke
				(width 0.1)
				(type default)
			)
			(layer "B.Fab")
		)
		(pad "1" smd rect
			(at 0 0)
			(size 0.508 0.508)
			(layers "B.Cu" "B.Mask" "B.Paste")
			(net "VSENSE_PVCCIO_CPU0_AVSP")
		)
		(pad "2" smd rect
			(at 0 0.889)
			(size 0.508 0.508)
			(layers "B.Cu" "B.Mask" "B.Paste")
			(net "PVCCIO_CPU0")
		)
		(zone
			(layer "B.Cu")
			(hatch none 0.5)
			(connect_pads
				(clearance 0)
			)
			(min_thickness 0.25)
			(keepout
				(tracks not_allowed)
				(vias allowed)
				(pads allowed)
				(copperpour not_allowed)
				(footprints allowed)
			)
			(placement
				(enabled no)
				(sheetname "")
			)
			(fill
				(thermal_gap 0.5)
				(thermal_bridge_width 0.5)
				(island_removal_mode 0)
			)
			(polygon
				(pts
					(xy 354.343208 -90.60688) (xy 354.851208 -90.60688) (xy 354.851208 -90.22588) (xy 354.343208 -90.22588)
				)
			)
		)
		(zone
			(layer "B.Cu")
			(hatch none 0.5)
			(connect_pads
				(clearance 0)
			)
			(min_thickness 0.25)
			(keepout
				(tracks allowed)
				(vias not_allowed)
				(pads allowed)
				(copperpour not_allowed)
				(footprints allowed)
			)
			(placement
				(enabled no)
				(sheetname "")
			)
			(fill
				(thermal_gap 0.5)
				(thermal_bridge_width 0.5)
				(island_removal_mode 0)
			)
			(polygon
				(pts
					(xy 354.343208 -90.22588) (xy 354.851208 -90.22588) (xy 354.851208 -90.60688) (xy 354.343208 -90.60688)
				)
			)
		)
	)
	(footprint ""
		(layer "B.Cu")
		(at 382.7653 -61.5315)
		(property "Reference" "U2T1"
			(at -2.91592 -1.22809 0)
			(unlocked yes)
			(layer "B.SilkS")
			(effects
				(font
					(size 0.7874 0.5842)
					(thickness 0.1524)
				)
				(justify left mirror)
			)
		)
		(property "Value" ""
			(at 0 0 0)
			(layer "B.Fab")
			(effects
				(font
					(size 1.27 1.27)
				)
				(justify mirror)
			)
		)
		(duplicate_pad_numbers_are_jumpers no)
		(fp_line
			(start -3.9243 -0.2794)
			(end -3.9243 4.7244)
			(stroke
				(width 0.1524)
				(type default)
			)
			(layer "B.SilkS")
		)
		(fp_line
			(start -3.9243 4.7244)
			(end -1.5367 4.7244)
			(stroke
				(width 0.1524)
				(type default)
			)
			(layer "B.SilkS")
		)
		(fp_line
			(start -3.1242 -0.2794)
			(end -3.1242 0.7366)
			(stroke
				(width 0.1524)
				(type default)
			)
			(layer "B.SilkS")
		)
		(fp_line
			(start -3.1242 0.7366)
			(end -2.3622 0.7366)
			(stroke
				(width 0.1524)
				(type default)
			)
			(layer "B.SilkS")
		)
		(fp_line
			(start -2.3622 -0.2794)
			(end -3.1242 -0.2794)
			(stroke
				(width 0.1524)
				(type default)
			)
			(layer "B.SilkS")
		)
		(fp_line
			(start -2.3622 0.7366)
			(end -2.3622 -0.2794)
			(stroke
				(width 0.1524)
				(type default)
			)
			(layer "B.SilkS")
		)
		(fp_line
			(start -1.5367 -0.2794)
			(end -3.9243 -0.2794)
			(stroke
				(width 0.1524)
				(type default)
			)
			(layer "B.SilkS")
		)
		(fp_line
			(start -1.5367 4.7244)
			(end -1.5367 -0.2794)
			(stroke
				(width 0.1524)
				(type default)
			)
			(layer "B.SilkS")
		)
		(fp_circle
			(center 0.9144 -1.0414)
			(end 1.1049 -1.0414)
			(stroke
				(width 0.381)
				(type default)
			)
			(fill no)
			(layer "B.SilkS")
		)
		(fp_poly
			(pts
				(xy -0.7366 -0.2794) (xy -4.7244 -0.2794) (xy -4.7244 4.7244) (xy -0.7366 4.7244)
			)
			(stroke
				(width 0)
				(type default)
			)
			(fill no)
			(layer "B.CrtYd")
		)
		(fp_line
			(start -4.7244 -0.2794)
			(end -4.7244 4.7244)
			(stroke
				(width 0.1)
				(type default)
			)
			(layer "B.Fab")
		)
		(fp_line
			(start -4.7244 4.7244)
			(end -0.7366 4.7244)
			(stroke
				(width 0.1)
				(type default)
			)
			(layer "B.Fab")
		)
		(fp_line
			(start -0.7366 -0.2794)
			(end -4.7244 -0.2794)
			(stroke
				(width 0.1)
				(type default)
			)
			(layer "B.Fab")
		)
		(fp_line
			(start -0.7366 4.7244)
			(end -0.7366 -0.2794)
			(stroke
				(width 0.1)
				(type default)
			)
			(layer "B.Fab")
		)
		(fp_circle
			(center 0.9144 -1.0414)
			(end 1.1049 -1.0414)
			(stroke
				(width 0.381)
				(type default)
			)
			(fill no)
			(layer "B.Fab")
		)
		(pad "1" smd rect
			(at 0 0 180)
			(size 2.159 0.381)
			(layers "B.Cu" "B.Mask" "B.Paste")
			(net "FM_BIOS_SPI_BMC_CTRL")
		)
		(pad "2" smd rect
			(at 0 0.635 180)
			(size 2.159 0.381)
			(layers "B.Cu" "B.Mask" "B.Paste")
			(net "SPI_PCH_IO2_R1")
		)
		(pad "3" smd rect
			(at 0 1.27 180)
			(size 2.159 0.381)
			(layers "B.Cu" "B.Mask" "B.Paste")
			(net "TP_SPI_SWITCH1_3")
		)
		(pad "4" smd rect
			(at 0 1.905 180)
			(size 2.159 0.381)
			(layers "B.Cu" "B.Mask" "B.Paste")
			(net "SPI_BIOS_SOCKET_IO2")
		)
		(pad "5" smd rect
			(at 0 2.54 180)
			(size 2.159 0.381)
			(layers "B.Cu" "B.Mask" "B.Paste")
			(net "SPI_PCH_IO3_R1")
		)
		(pad "6" smd rect
			(at 0 3.175 180)
			(size 2.159 0.381)
			(layers "B.Cu" "B.Mask" "B.Paste")
			(net "TP_SPI_SWITCH1_6")
		)
		(pad "7" smd rect
			(at 0 3.81 180)
			(size 2.159 0.381)
			(layers "B.Cu" "B.Mask" "B.Paste")
			(net "SPI_BIOS_SOCKET_IO3")
		)
		(pad "8" smd rect
			(at 0 4.445 180)
			(size 2.159 0.381)
			(layers "B.Cu" "B.Mask" "B.Paste")
			(net "GND")
		)
		(pad "9" smd rect
			(at -5.461 4.445 180)
			(size 2.159 0.381)
			(layers "B.Cu" "B.Mask" "B.Paste")
			(net "TP_SPI_SWITCH1_9")
		)
		(pad "10" smd rect
			(at -5.461 3.81 180)
			(size 2.159 0.381)
			(layers "B.Cu" "B.Mask" "B.Paste")
			(net "TP_SPI_SWITCH1_10")
		)
		(pad "11" smd rect
			(at -5.461 3.175 180)
			(size 2.159 0.381)
			(layers "B.Cu" "B.Mask" "B.Paste")
			(net "TP_SPI_SWITCH1_11")
		)
		(pad "12" smd rect
			(at -5.461 2.54 180)
			(size 2.159 0.381)
			(layers "B.Cu" "B.Mask" "B.Paste")
			(net "TP_SPI_SWITCH1_12")
		)
		(pad "13" smd rect
			(at -5.461 1.905 180)
			(size 2.159 0.381)
			(layers "B.Cu" "B.Mask" "B.Paste")
			(net "TP_SPI_SWITCH1_13")
		)
		(pad "14" smd rect
			(at -5.461 1.27 180)
			(size 2.159 0.381)
			(layers "B.Cu" "B.Mask" "B.Paste")
			(net "TP_SPI_SWITCH1_14")
		)
		(pad "15" smd rect
			(at -5.461 0.635 180)
			(size 2.159 0.381)
			(layers "B.Cu" "B.Mask" "B.Paste")
			(net "GND")
		)
		(pad "16" smd rect
			(at -5.461 0 180)
			(size 2.159 0.381)
			(layers "B.Cu" "B.Mask" "B.Paste")
			(net "P3V3_STBY")
		)
	)
)
